# T6G (Grand Teton) — schematic netlist excerpt (pin names and nets, part order shuffled) for the footprints in the layout excerpt that follows; sources: Cadence DE-HDL packaged netlist, KiCad conversion of 04192023_DAF0TMB3IC0_F0TG_MB_C_brd_V02_OCP.brd

R1331  Q_RES  0 5% EMPTY  pkg 0402LF  page 159 : A = I3C_SPD_DDRAF_CPU0_BYPASS_SDA ; B = I3C_SPD_DDRAF_CPU0_SDA
R2787  Q_RES  0 5% CHIP  pkg 0402LF  page 234 : A = USB2_HUB_SWB_DN ; B = USB2_HUB_BUF_SWB_R_DN

(kicad_pcb
	(version 20260206)
	(generator "pcbnew")
	(generator_version "10.0")
	(general
		(thickness 1.6)
		(legacy_teardrops no)
	)
	(paper "A4")
	(title_block
		(title "04192023_DAF0TMB3IC0_F0TG_MB_C_brd_V02_OCP.brd")
		(comment 1 "Grand Teton / footprints 1253-1254 of 8354")
	)
	(layers
		(0 "F.Cu" signal "TOP")
		(4 "In1.Cu" signal "GND")
		(6 "In2.Cu" signal "IN1")
		(8 "In3.Cu" signal "GND1")
		(10 "In4.Cu" signal "IN2")
		(12 "In5.Cu" signal "GND2")
		(14 "In6.Cu" signal "IN3")
		(16 "In7.Cu" signal "GND3")
		(18 "In8.Cu" signal "VCC")
		(20 "In9.Cu" signal "VCC1")
		(22 "In10.Cu" signal "GND4")
		(24 "In11.Cu" signal "IN4")
		(26 "In12.Cu" signal "GND5")
		(28 "In13.Cu" signal "IN5")
		(30 "In14.Cu" signal "GND6")
		(32 "In15.Cu" signal "IN6")
		(34 "In16.Cu" signal "GND7")
		(2 "B.Cu" signal "BOTTOM")
		(9 "F.Adhes" user "F.Adhesive")
		(11 "B.Adhes" user "B.Adhesive")
		(13 "F.Paste" user "Package Geometry/Pastemask Top")
		(15 "B.Paste" user "Package Geometry/Pastemask Bottom")
		(5 "F.SilkS" user "Ref Des/Silkscreen Top")
		(7 "B.SilkS" user "Ref Des/Silkscreen Bottom")
		(1 "F.Mask" user "Board Geometry/Soldermask Top")
		(3 "B.Mask" user "Board Geometry/Soldermask Bottom")
		(17 "Dwgs.User" user "User.Drawings")
		(19 "Cmts.User" user "User.Comments")
		(21 "Eco1.User" user "User.Eco1")
		(23 "Eco2.User" user "User.Eco2")
		(25 "Edge.Cuts" user "Board Geometry/Outline")
		(27 "Margin" user)
		(31 "F.CrtYd" user "Package Geometry/Place Bound Top")
		(29 "B.CrtYd" user "Package Geometry/Place Bound Bottom")
		(35 "F.Fab" user "Ref Des/Assembly Top")
		(33 "B.Fab" user "Ref Des/Assembly Bottom")
	)
	(footprint ""
		(layer "F.Cu")
		(at 297.32605 -150.538942 180)
		(property "Reference" "R1331"
			(at 0 0 180)
			(layer "F.SilkS")
			(hide yes)
			(effects
				(font
					(size 1.27 1.27)
				)
			)
		)
		(property "Value" ""
			(at 0 0 180)
			(layer "F.Fab")
			(effects
				(font
					(size 1.27 1.27)
				)
			)
		)
		(duplicate_pad_numbers_are_jumpers no)
		(fp_line
			(start 0.7874 0.4064)
			(end -0.7874 0.4064)
			(stroke
				(width 0.1524)
				(type default)
			)
			(layer "F.SilkS")
		)
		(fp_line
			(start 0.7874 -0.4064)
			(end 0.7874 0.4064)
			(stroke
				(width 0.1524)
				(type default)
			)
			(layer "F.SilkS")
		)
		(fp_line
			(start -0.7874 0.4064)
			(end -0.7874 -0.4064)
			(stroke
				(width 0.1524)
				(type default)
			)
			(layer "F.SilkS")
		)
		(fp_line
			(start -0.7874 -0.4064)
			(end 0.7874 -0.4064)
			(stroke
				(width 0.1524)
				(type default)
			)
			(layer "F.SilkS")
		)
		(fp_line
			(start 0.67945 0.3048)
			(end 0.120396 0.3048)
			(stroke
				(width 0.1)
				(type default)
			)
			(layer "F.Fab")
		)
		(fp_line
			(start 0.67945 -0.3048)
			(end 0.67945 0.3048)
			(stroke
				(width 0.1)
				(type default)
			)
			(layer "F.Fab")
		)
		(fp_line
			(start 0.12065 -0.2794)
			(end 0.12065 -0.3048)
			(stroke
				(width 0.1)
				(type default)
			)
			(layer "F.Fab")
		)
		(fp_line
			(start 0.12065 -0.3048)
			(end 0.67945 -0.3048)
			(stroke
				(width 0.1)
				(type default)
			)
			(layer "F.Fab")
		)
		(fp_line
			(start 0.120396 0.3048)
			(end 0.120396 0.2794)
			(stroke
				(width 0.1)
				(type default)
			)
			(layer "F.Fab")
		)
		(fp_line
			(start 0.120396 0.2794)
			(end -0.12065 0.2794)
			(stroke
				(width 0.1)
				(type default)
			)
			(layer "F.Fab")
		)
		(fp_line
			(start -0.12065 0.3048)
			(end -0.67945 0.3048)
			(stroke
				(width 0.1)
				(type default)
			)
			(layer "F.Fab")
		)
		(fp_line
			(start -0.12065 0.2794)
			(end -0.12065 0.3048)
			(stroke
				(width 0.1)
				(type default)
			)
			(layer "F.Fab")
		)
		(fp_line
			(start -0.12065 -0.2794)
			(end 0.12065 -0.2794)
			(stroke
				(width 0.1)
				(type default)
			)
			(layer "F.Fab")
		)
		(fp_line
			(start -0.12065 -0.305054)
			(end -0.12065 -0.2794)
			(stroke
				(width 0.1)
				(type default)
			)
			(layer "F.Fab")
		)
		(fp_line
			(start -0.67945 0.3048)
			(end -0.67945 -0.305054)
			(stroke
				(width 0.1)
				(type default)
			)
			(layer "F.Fab")
		)
		(fp_line
			(start -0.67945 -0.305054)
			(end -0.12065 -0.305054)
			(stroke
				(width 0.1)
				(type default)
			)
			(layer "F.Fab")
		)
		(pad "1" smd rect
			(at -0.40005 0)
			(size 0.4572 0.508)
			(layers "F.Cu" "F.Mask" "F.Paste")
			(net "I3C_SPD_DDRAF_CPU0_BYPASS_SDA")
		)
		(pad "2" smd rect
			(at 0.40005 0)
			(size 0.4572 0.508)
			(layers "F.Cu" "F.Mask" "F.Paste")
			(net "I3C_SPD_DDRAF_CPU0_SDA")
		)
	)
	(footprint ""
		(layer "F.Cu")
		(at 12.786106 -105.50398 90)
		(property "Reference" "R2787"
			(at 0 0 90)
			(layer "F.SilkS")
			(hide yes)
			(effects
				(font
					(size 1.27 1.27)
				)
			)
		)
		(property "Value" ""
			(at 0 0 90)
			(layer "F.Fab")
			(effects
				(font
					(size 1.27 1.27)
				)
			)
		)
		(duplicate_pad_numbers_are_jumpers no)
		(fp_line
			(start 0.7874 -0.4064)
			(end 0.7874 0.4064)
			(stroke
				(width 0.1524)
				(type default)
			)
			(layer "F.SilkS")
		)
		(fp_line
			(start -0.7874 -0.4064)
			(end 0.7874 -0.4064)
			(stroke
				(width 0.1524)
				(type default)
			)
			(layer "F.SilkS")
		)
		(fp_line
			(start 0.7874 0.4064)
			(end -0.7874 0.4064)
			(stroke
				(width 0.1524)
				(type default)
			)
			(layer "F.SilkS")
		)
		(fp_line
			(start -0.7874 0.4064)
			(end -0.7874 -0.4064)
			(stroke
				(width 0.1524)
				(type default)
			)
			(layer "F.SilkS")
		)
		(fp_line
			(start -0.12065 -0.305054)
			(end -0.12065 -0.2794)
			(stroke
				(width 0.1)
				(type default)
			)
			(layer "F.Fab")
		)
		(fp_line
			(start -0.67945 -0.305054)
			(end -0.12065 -0.305054)
			(stroke
				(width 0.1)
				(type default)
			)
			(layer "F.Fab")
		)
		(fp_line
			(start 0.67945 -0.3048)
			(end 0.67945 0.3048)
			(stroke
				(width 0.1)
				(type default)
			)
			(layer "F.Fab")
		)
		(fp_line
			(start 0.12065 -0.3048)
			(end 0.67945 -0.3048)
			(stroke
				(width 0.1)
				(type default)
			)
			(layer "F.Fab")
		)
		(fp_line
			(start 0.12065 -0.2794)
			(end 0.12065 -0.3048)
			(stroke
				(width 0.1)
				(type default)
			)
			(layer "F.Fab")
		)
		(fp_line
			(start -0.12065 -0.2794)
			(end 0.12065 -0.2794)
			(stroke
				(width 0.1)
				(type default)
			)
			(layer "F.Fab")
		)
		(fp_line
			(start 0.120396 0.2794)
			(end -0.12065 0.2794)
			(stroke
				(width 0.1)
				(type default)
			)
			(layer "F.Fab")
		)
		(fp_line
			(start -0.12065 0.2794)
			(end -0.12065 0.3048)
			(stroke
				(width 0.1)
				(type default)
			)
			(layer "F.Fab")
		)
		(fp_line
			(start 0.67945 0.3048)
			(end 0.120396 0.3048)
			(stroke
				(width 0.1)
				(type default)
			)
			(layer "F.Fab")
		)
		(fp_line
			(start 0.120396 0.3048)
			(end 0.120396 0.2794)
			(stroke
				(width 0.1)
				(type default)
			)
			(layer "F.Fab")
		)
		(fp_line
			(start -0.12065 0.3048)
			(end -0.67945 0.3048)
			(stroke
				(width 0.1)
				(type default)
			)
			(layer "F.Fab")
		)
		(fp_line
			(start -0.67945 0.3048)
			(end -0.67945 -0.305054)
			(stroke
				(width 0.1)
				(type default)
			)
			(layer "F.Fab")
		)
		(pad "1" smd rect
			(at -0.40005 0 270)
			(size 0.4572 0.508)
			(layers "F.Cu" "F.Mask" "F.Paste")
			(net "USB2_HUB_SWB_DN")
		)
		(pad "2" smd rect
			(at 0.40005 0 270)
			(size 0.4572 0.508)
			(layers "F.Cu" "F.Mask" "F.Paste")
			(net "USB2_HUB_BUF_SWB_R_DN")
		)
	)
)
